(kicad_pcb
	(version 20260206)
	(generator "pcbnew")
	(generator_version "10.0")
	(general
		(thickness 1.6)
		(legacy_teardrops no)
	)
	(paper "A4")
	(title_block
		(title "Bryce Canyon_R.DPB_16317-1_OCP.brd")
		(comment 1 "Bryce Canyon / footprints 1594-1601 of 2099")
	)
	(layers
		(0 "F.Cu" signal "TOP")
		(4 "In1.Cu" signal "L2GND")
		(6 "In2.Cu" signal "L3")
		(8 "In3.Cu" signal "L4VCC")
		(10 "In4.Cu" signal "L5VCC")
		(12 "In5.Cu" signal "L6")
		(14 "In6.Cu" signal "L7GND")
		(2 "B.Cu" signal "BOTTOM")
		(9 "F.Adhes" user "F.Adhesive")
		(11 "B.Adhes" user "B.Adhesive")
		(13 "F.Paste" user "Package Geometry/Pastemask Top")
		(15 "B.Paste" user "Package Geometry/Pastemask Bottom")
		(5 "F.SilkS" user "Ref Des/Silkscreen Top")
		(7 "B.SilkS" user "Ref Des/Silkscreen Bottom")
		(1 "F.Mask" user "Board Geometry/Soldermask Top")
		(3 "B.Mask" user "Board Geometry/Soldermask Bottom")
		(17 "Dwgs.User" user "User.Drawings")
		(19 "Cmts.User" user "User.Comments")
		(21 "Eco1.User" user "User.Eco1")
		(23 "Eco2.User" user "User.Eco2")
		(25 "Edge.Cuts" user "Board Geometry/Outline")
		(27 "Margin" user)
		(31 "F.CrtYd" user "Package Geometry/Place Bound Top")
		(29 "B.CrtYd" user "Package Geometry/Place Bound Bottom")
		(35 "F.Fab" user "Ref Des/Assembly Top")
		(33 "B.Fab" user "Ref Des/Assembly Bottom")
	)
	(footprint ""
		(layer "F.Cu")
		(at 447.421 -148.209 90)
		(property "Reference" "R576"
			(at 0 0 90)
			(layer "F.SilkS")
			(hide yes)
			(effects
				(font
					(size 1.27 1.27)
				)
			)
		)
		(property "Value" "10KR2F-2-GP"
			(at 0.064008 -3.993896 90)
			(unlocked yes)
			(layer "F.Fab")
			(hide yes)
			(effects
				(font
					(size 1.016 1.016)
					(thickness 0.1524)
				)
			)
		)
		(property "Device Type" "R402H16"
			(at 0.064008 -5.517896 90)
			(unlocked yes)
			(layer "F.Fab")
			(hide yes)
			(effects
				(font
					(size 1.016 1.016)
					(thickness 0.1524)
				)
			)
		)
		(duplicate_pad_numbers_are_jumpers no)
		(fp_line
			(start 0.508 -0.9398)
			(end -0.508 -0.9398)
			(stroke
				(width 0.1524)
				(type default)
			)
			(layer "F.SilkS")
		)
		(fp_line
			(start -0.508 -0.9398)
			(end -0.508 0.9398)
			(stroke
				(width 0.1524)
				(type default)
			)
			(layer "F.SilkS")
		)
		(fp_rect
			(start -0.508 0.9398)
			(end 0.508 -0.9398)
			(stroke
				(width 0)
				(type default)
			)
			(fill no)
			(layer "F.CrtYd")
		)
		(fp_rect
			(start -0.508 0.9398)
			(end 0.508 -0.9398)
			(stroke
				(width 0)
				(type default)
			)
			(fill no)
			(layer "F.Fab")
		)
		(pad "1" smd custom
			(at 0 -0.4445 90)
			(size 0.1397 0.1397)
			(layers "F.Cu" "F.Mask" "F.Paste")
			(net "P3V3_STBY_B")
			(options
				(clearance outline)
				(anchor circle)
			)
			(primitives
				(gr_poly
					(pts
						(arc
							(start -0.1778 -0.2794)
							(mid -0.249642 -0.249642)
							(end -0.2794 -0.1778)
						)
						(arc
							(start -0.2794 0.1778)
							(mid -0.249642 0.249642)
							(end -0.1778 0.2794)
						)
						(arc
							(start 0.1778 0.2794)
							(mid 0.249642 0.249642)
							(end 0.2794 0.1778)
						)
						(arc
							(start 0.2794 -0.1778)
							(mid 0.249642 -0.249642)
							(end 0.1778 -0.2794)
						)
					)
					(width 0)
					(fill yes)
				)
			)
		)
		(pad "2" smd custom
			(at 0 0.4445 90)
			(size 0.1397 0.1397)
			(layers "F.Cu" "F.Mask" "F.Paste")
			(net "HDD_PRSNT_22")
			(options
				(clearance outline)
				(anchor circle)
			)
			(primitives
				(gr_poly
					(pts
						(arc
							(start -0.1778 -0.2794)
							(mid -0.249642 -0.249642)
							(end -0.2794 -0.1778)
						)
						(arc
							(start -0.2794 0.1778)
							(mid -0.249642 0.249642)
							(end -0.1778 0.2794)
						)
						(arc
							(start 0.1778 0.2794)
							(mid 0.249642 0.249642)
							(end 0.2794 0.1778)
						)
						(arc
							(start 0.2794 -0.1778)
							(mid 0.249642 -0.249642)
							(end 0.1778 -0.2794)
						)
					)
					(width 0)
					(fill yes)
				)
			)
		)
	)
	(footprint ""
		(layer "F.Cu")
		(at 54.4576 -133.4008 -90)
		(property "Reference" "R377"
			(at 0 0 270)
			(layer "F.SilkS")
			(hide yes)
			(effects
				(font
					(size 1.27 1.27)
				)
			)
		)
		(property "Value" "1KR2F-3-GP"
			(at 0.064008 -3.993896 270)
			(unlocked yes)
			(layer "F.Fab")
			(hide yes)
			(effects
				(font
					(size 1.016 1.016)
					(thickness 0.1524)
				)
			)
		)
		(property "Device Type" "R402H16"
			(at 0.064008 -5.517896 270)
			(unlocked yes)
			(layer "F.Fab")
			(hide yes)
			(effects
				(font
					(size 1.016 1.016)
					(thickness 0.1524)
				)
			)
		)
		(duplicate_pad_numbers_are_jumpers no)
		(fp_line
			(start -0.508 -0.9398)
			(end -0.508 0.9398)
			(stroke
				(width 0.1524)
				(type default)
			)
			(layer "F.SilkS")
		)
		(fp_line
			(start 0.508 -0.9398)
			(end -0.508 -0.9398)
			(stroke
				(width 0.1524)
				(type default)
			)
			(layer "F.SilkS")
		)
		(fp_rect
			(start -0.508 0.9398)
			(end 0.508 -0.9398)
			(stroke
				(width 0)
				(type default)
			)
			(fill no)
			(layer "F.CrtYd")
		)
		(fp_rect
			(start -0.508 0.9398)
			(end 0.508 -0.9398)
			(stroke
				(width 0)
				(type default)
			)
			(fill no)
			(layer "F.Fab")
		)
		(pad "1" smd custom
			(at 0 -0.4445 270)
			(size 0.1397 0.1397)
			(layers "F.Cu" "F.Mask" "F.Paste")
			(net "P3V3_STBY_B")
			(options
				(clearance outline)
				(anchor circle)
			)
			(primitives
				(gr_poly
					(pts
						(arc
							(start -0.1778 -0.2794)
							(mid -0.249642 -0.249642)
							(end -0.2794 -0.1778)
						)
						(arc
							(start -0.2794 0.1778)
							(mid -0.249642 0.249642)
							(end -0.1778 0.2794)
						)
						(arc
							(start 0.1778 0.2794)
							(mid 0.249642 0.249642)
							(end 0.2794 0.1778)
						)
						(arc
							(start 0.2794 -0.1778)
							(mid 0.249642 -0.249642)
							(end 0.1778 -0.2794)
						)
					)
					(width 0)
					(fill yes)
				)
			)
		)
		(pad "2" smd custom
			(at 0 0.4445 270)
			(size 0.1397 0.1397)
			(layers "F.Cu" "F.Mask" "F.Paste")
			(net "SW_PWR_R_HDD13")
			(options
				(clearance outline)
				(anchor circle)
			)
			(primitives
				(gr_poly
					(pts
						(arc
							(start -0.1778 -0.2794)
							(mid -0.249642 -0.249642)
							(end -0.2794 -0.1778)
						)
						(arc
							(start -0.2794 0.1778)
							(mid -0.249642 0.249642)
							(end -0.1778 0.2794)
						)
						(arc
							(start 0.1778 0.2794)
							(mid 0.249642 0.249642)
							(end 0.2794 0.1778)
						)
						(arc
							(start 0.2794 -0.1778)
							(mid 0.249642 -0.249642)
							(end 0.1778 -0.2794)
						)
					)
					(width 0)
					(fill yes)
				)
			)
		)
	)
	(footprint ""
		(layer "F.Cu")
		(at 32.508952 -248.750074 -90)
		(property "Reference" "VIA2"
			(at 0 0 270)
			(layer "F.SilkS")
			(hide yes)
			(effects
				(font
					(size 1.27 1.27)
				)
			)
		)
		(property "Value" "100OHM-8L-2D36MM-L16-GP"
			(at -3.4036 -0.4572 270)
			(unlocked yes)
			(layer "F.Fab")
			(hide yes)
			(effects
				(font
					(size 1.016 1.016)
					(thickness 0.1524)
				)
			)
		)
		(property "Device Type" "VIA-PCIE-4P-427097"
			(at -3.4036 -1.9812 270)
			(unlocked yes)
			(layer "F.Fab")
			(hide yes)
			(effects
				(font
					(size 1.016 1.016)
					(thickness 0.1524)
				)
			)
		)
		(duplicate_pad_numbers_are_jumpers no)
		(fp_rect
			(start -2.1336 0.4826)
			(end 2.1336 -0.4826)
			(stroke
				(width 0)
				(type default)
			)
			(fill no)
			(layer "F.CrtYd")
		)
		(fp_rect
			(start -2.1336 0.4826)
			(end 2.1336 -0.4826)
			(stroke
				(width 0)
				(type default)
			)
			(fill no)
			(layer "F.Fab")
		)
		(pad "1" thru_hole circle
			(at -1.651 0 270)
			(size 0.508 0.508)
			(drill 0.254)
			(layers "*.Cu" "*.Mask")
			(remove_unused_layers no)
			(net "GND")
			(clearance 0.2286)
			(thermal_gap 0.2286)
		)
		(pad "2" thru_hole circle
			(at -0.635 0 270)
			(size 0.508 0.508)
			(drill 0.254)
			(layers "*.Cu" "*.Mask")
			(remove_unused_layers no)
			(net "PHY_DRV_B_TO_SCC_B_0_DP")
			(clearance 0.2286)
			(thermal_gap 0.2286)
		)
		(pad "3" thru_hole circle
			(at 0.635 0 270)
			(size 0.508 0.508)
			(drill 0.254)
			(layers "*.Cu" "*.Mask")
			(remove_unused_layers no)
			(net "PHY_DRV_B_TO_SCC_B_0_DN")
			(clearance 0.2286)
			(thermal_gap 0.2286)
		)
		(pad "4" thru_hole circle
			(at 1.651 0 270)
			(size 0.508 0.508)
			(drill 0.254)
			(layers "*.Cu" "*.Mask")
			(remove_unused_layers no)
			(net "GND")
			(clearance 0.2286)
			(thermal_gap 0.2286)
		)
	)
	(footprint ""
		(layer "F.Cu")
		(at 82.042 -35.687 90)
		(property "Reference" "R669"
			(at 0 0 90)
			(layer "F.SilkS")
			(hide yes)
			(effects
				(font
					(size 1.27 1.27)
				)
			)
		)
		(property "Value" "2R6F-GP"
			(at -0.0508 -4.8514 90)
			(unlocked yes)
			(layer "F.Fab")
			(hide yes)
			(effects
				(font
					(size 1.016 1.016)
					(thickness 0.1524)
				)
			)
		)
		(property "Device Type" "R1206H26"
			(at 0 -6.3754 90)
			(unlocked yes)
			(layer "F.Fab")
			(hide yes)
			(effects
				(font
					(size 1.016 1.016)
					(thickness 0.1524)
				)
			)
		)
		(duplicate_pad_numbers_are_jumpers no)
		(fp_line
			(start 1.016 -2.2352)
			(end 1.016 2.2352)
			(stroke
				(width 0.1524)
				(type default)
			)
			(layer "F.SilkS")
		)
		(fp_line
			(start -1.016 -2.2352)
			(end 1.016 -2.2352)
			(stroke
				(width 0.1524)
				(type default)
			)
			(layer "F.SilkS")
		)
		(fp_line
			(start 1.016 2.2352)
			(end -1.016 2.2352)
			(stroke
				(width 0.1524)
				(type default)
			)
			(layer "F.SilkS")
		)
		(fp_line
			(start -1.016 2.2352)
			(end -1.016 -2.2352)
			(stroke
				(width 0.1524)
				(type default)
			)
			(layer "F.SilkS")
		)
		(fp_rect
			(start -1.0922 2.3114)
			(end 1.0922 -2.3114)
			(stroke
				(width 0)
				(type default)
			)
			(fill no)
			(layer "F.CrtYd")
		)
		(fp_poly
			(pts
				(xy -1.0922 -2.3114) (xy 1.0922 -2.3114) (xy 1.0922 2.3114) (xy -1.0922 2.3114)
			)
			(stroke
				(width 0)
				(type default)
			)
			(fill no)
			(layer "F.Fab")
		)
		(pad "1" smd rect
			(at 0 -1.397 90)
			(size 1.651 1.27)
			(layers "F.Cu" "F.Mask" "F.Paste")
			(net "P12V_HDD26")
		)
		(pad "2" smd rect
			(at 0 1.397 90)
			(size 1.651 1.27)
			(layers "F.Cu" "F.Mask" "F.Paste")
			(net "12V_PRE_26")
		)
	)
	(footprint ""
		(layer "F.Cu")
		(at 170.84675 -217.337386 -90)
		(property "Reference" "R226"
			(at 0 0 270)
			(layer "F.SilkS")
			(hide yes)
			(effects
				(font
					(size 1.27 1.27)
				)
			)
		)
		(property "Value" "4K7R2F-GP"
			(at 0.064008 -3.993896 270)
			(unlocked yes)
			(layer "F.Fab")
			(hide yes)
			(effects
				(font
					(size 1.016 1.016)
					(thickness 0.1524)
				)
			)
		)
		(property "Device Type" "R402H16"
			(at 0.064008 -5.517896 270)
			(unlocked yes)
			(layer "F.Fab")
			(hide yes)
			(effects
				(font
					(size 1.016 1.016)
					(thickness 0.1524)
				)
			)
		)
		(duplicate_pad_numbers_are_jumpers no)
		(fp_line
			(start -0.508 -0.9398)
			(end -0.508 0.9398)
			(stroke
				(width 0.1524)
				(type default)
			)
			(layer "F.SilkS")
		)
		(fp_line
			(start 0.508 -0.9398)
			(end -0.508 -0.9398)
			(stroke
				(width 0.1524)
				(type default)
			)
			(layer "F.SilkS")
		)
		(fp_rect
			(start -0.508 0.9398)
			(end 0.508 -0.9398)
			(stroke
				(width 0)
				(type default)
			)
			(fill no)
			(layer "F.CrtYd")
		)
		(fp_rect
			(start -0.508 0.9398)
			(end 0.508 -0.9398)
			(stroke
				(width 0)
				(type default)
			)
			(fill no)
			(layer "F.Fab")
		)
		(pad "1" smd custom
			(at 0 -0.4445 270)
			(size 0.1397 0.1397)
			(layers "F.Cu" "F.Mask" "F.Paste")
			(net "DRIVE_B_5_FLT_LED")
			(options
				(clearance outline)
				(anchor circle)
			)
			(primitives
				(gr_poly
					(pts
						(arc
							(start -0.1778 -0.2794)
							(mid -0.249642 -0.249642)
							(end -0.2794 -0.1778)
						)
						(arc
							(start -0.2794 0.1778)
							(mid -0.249642 0.249642)
							(end -0.1778 0.2794)
						)
						(arc
							(start 0.1778 0.2794)
							(mid 0.249642 0.249642)
							(end 0.2794 0.1778)
						)
						(arc
							(start 0.2794 -0.1778)
							(mid 0.249642 -0.249642)
							(end 0.1778 -0.2794)
						)
					)
					(width 0)
					(fill yes)
				)
			)
		)
		(pad "2" smd custom
			(at 0 0.4445 270)
			(size 0.1397 0.1397)
			(layers "F.Cu" "F.Mask" "F.Paste")
			(net "GND")
			(options
				(clearance outline)
				(anchor circle)
			)
			(primitives
				(gr_poly
					(pts
						(arc
							(start -0.1778 -0.2794)
							(mid -0.249642 -0.249642)
							(end -0.2794 -0.1778)
						)
						(arc
							(start -0.2794 0.1778)
							(mid -0.249642 0.249642)
							(end -0.1778 0.2794)
						)
						(arc
							(start 0.1778 0.2794)
							(mid 0.249642 0.249642)
							(end 0.2794 0.1778)
						)
						(arc
							(start 0.2794 -0.1778)
							(mid 0.249642 -0.249642)
							(end 0.1778 -0.2794)
						)
					)
					(width 0)
					(fill yes)
				)
			)
		)
	)
	(footprint ""
		(layer "F.Cu")
		(at 368.427 -16.764 180)
		(property "Reference" "R796"
			(at 0 0 180)
			(layer "F.SilkS")
			(hide yes)
			(effects
				(font
					(size 1.27 1.27)
				)
			)
		)
		(property "Value" "4K7R2J-2-GP"
			(at 0.064008 -3.993896 180)
			(unlocked yes)
			(layer "F.Fab")
			(hide yes)
			(effects
				(font
					(size 1.016 1.016)
					(thickness 0.1524)
				)
			)
		)
		(property "Device Type" "R402H16"
			(at 0.064008 -5.517896 180)
			(unlocked yes)
			(layer "F.Fab")
			(hide yes)
			(effects
				(font
					(size 1.016 1.016)
					(thickness 0.1524)
				)
			)
		)
		(duplicate_pad_numbers_are_jumpers no)
		(fp_line
			(start 0.508 -0.9398)
			(end -0.508 -0.9398)
			(stroke
				(width 0.1524)
				(type default)
			)
			(layer "F.SilkS")
		)
		(fp_line
			(start -0.508 -0.9398)
			(end -0.508 0.9398)
			(stroke
				(width 0.1524)
				(type default)
			)
			(layer "F.SilkS")
		)
		(fp_rect
			(start -0.508 0.9398)
			(end 0.508 -0.9398)
			(stroke
				(width 0)
				(type default)
			)
			(fill no)
			(layer "F.CrtYd")
		)
		(fp_rect
			(start -0.508 0.9398)
			(end 0.508 -0.9398)
			(stroke
				(width 0)
				(type default)
			)
			(fill no)
			(layer "F.Fab")
		)
		(pad "1" smd custom
			(at 0 -0.4445 180)
			(size 0.1397 0.1397)
			(layers "F.Cu" "F.Mask" "F.Paste")
			(net "P12V_B")
			(options
				(clearance outline)
				(anchor circle)
			)
			(primitives
				(gr_poly
					(pts
						(arc
							(start -0.1778 -0.2794)
							(mid -0.249642 -0.249642)
							(end -0.2794 -0.1778)
						)
						(arc
							(start -0.2794 0.1778)
							(mid -0.249642 0.249642)
							(end -0.1778 0.2794)
						)
						(arc
							(start 0.1778 0.2794)
							(mid 0.249642 0.249642)
							(end 0.2794 0.1778)
						)
						(arc
							(start 0.2794 -0.1778)
							(mid 0.249642 -0.249642)
							(end 0.1778 -0.2794)
						)
					)
					(width 0)
					(fill yes)
				)
			)
		)
		(pad "2" smd custom
			(at 0 0.4445 180)
			(size 0.1397 0.1397)
			(layers "F.Cu" "F.Mask" "F.Paste")
			(net "SW_HDD_R31")
			(options
				(clearance outline)
				(anchor circle)
			)
			(primitives
				(gr_poly
					(pts
						(arc
							(start -0.1778 -0.2794)
							(mid -0.249642 -0.249642)
							(end -0.2794 -0.1778)
						)
						(arc
							(start -0.2794 0.1778)
							(mid -0.249642 0.249642)
							(end -0.1778 0.2794)
						)
						(arc
							(start 0.1778 0.2794)
							(mid 0.249642 0.249642)
							(end 0.2794 0.1778)
						)
						(arc
							(start 0.2794 -0.1778)
							(mid 0.249642 -0.249642)
							(end 0.1778 -0.2794)
						)
					)
					(width 0)
					(fill yes)
				)
			)
		)
	)
	(footprint ""
		(layer "F.Cu")
		(at 253.492 -283.718)
		(property "Reference" "C689"
			(at 0 0 0)
			(layer "F.SilkS")
			(hide yes)
			(effects
				(font
					(size 1.27 1.27)
				)
			)
		)
		(property "Value" "SC1U16V3KX-5GP"
			(at 0 -2.8194 0)
			(unlocked yes)
			(layer "F.Fab")
			(hide yes)
			(effects
				(font
					(size 1.016 1.016)
					(thickness 0.1524)
				)
			)
		)
		(property "Device Type" "C603H36"
			(at 0 -4.3434 0)
			(unlocked yes)
			(layer "F.Fab")
			(hide yes)
			(effects
				(font
					(size 1.016 1.016)
					(thickness 0.1524)
				)
			)
		)
		(duplicate_pad_numbers_are_jumpers no)
		(fp_line
			(start 0.508 0)
			(end -0.508 0)
			(stroke
				(width 0.2032)
				(type default)
			)
			(layer "F.SilkS")
		)
		(fp_rect
			(start -0.5842 1.3335)
			(end 0.5842 -1.3335)
			(stroke
				(width 0)
				(type default)
			)
			(fill no)
			(layer "F.CrtYd")
		)
		(fp_rect
			(start -0.5842 1.3335)
			(end 0.5842 -1.3335)
			(stroke
				(width 0)
				(type default)
			)
			(fill no)
			(layer "F.Fab")
		)
		(pad "1" smd custom
			(at 0 -0.762)
			(size 0.2159 0.2159)
			(layers "F.Cu" "F.Mask" "F.Paste")
			(net "P3V3_STBY_VCC")
			(options
				(clearance outline)
				(anchor circle)
			)
			(primitives
				(gr_poly
					(pts
						(arc
							(start -0.3302 -0.4318)
							(mid -0.402042 -0.402042)
							(end -0.4318 -0.3302)
						)
						(arc
							(start -0.4318 0.3302)
							(mid -0.402042 0.402042)
							(end -0.3302 0.4318)
						)
						(arc
							(start 0.3302 0.4318)
							(mid 0.402042 0.402042)
							(end 0.4318 0.3302)
						)
						(arc
							(start 0.4318 -0.3302)
							(mid 0.402042 -0.402042)
							(end 0.3302 -0.4318)
						)
					)
					(width 0)
					(fill yes)
				)
			)
		)
		(pad "2" smd custom
			(at 0 0.762)
			(size 0.2159 0.2159)
			(layers "F.Cu" "F.Mask" "F.Paste")
			(net "GND")
			(options
				(clearance outline)
				(anchor circle)
			)
			(primitives
				(gr_poly
					(pts
						(arc
							(start -0.3302 -0.4318)
							(mid -0.402042 -0.402042)
							(end -0.4318 -0.3302)
						)
						(arc
							(start -0.4318 0.3302)
							(mid -0.402042 0.402042)
							(end -0.3302 0.4318)
						)
						(arc
							(start 0.3302 0.4318)
							(mid 0.402042 0.402042)
							(end 0.4318 0.3302)
						)
						(arc
							(start 0.4318 -0.3302)
							(mid 0.402042 -0.402042)
							(end 0.3302 -0.4318)
						)
					)
					(width 0)
					(fill yes)
				)
			)
		)
	)
	(footprint ""
		(layer "F.Cu")
		(at 146.685 -134.493 180)
		(property "Reference" "Q71"
			(at 0 0 180)
			(layer "F.SilkS")
			(hide yes)
			(effects
				(font
					(size 1.27 1.27)
				)
			)
		)
		(property "Value" "2N7002KDW-GP"
			(at -2.3622 -8.2042 180)
			(unlocked yes)
			(layer "F.Fab")
			(hide yes)
			(effects
				(font
					(size 1.016 1.016)
					(thickness 0.1524)
				)
			)
		)
		(property "Device Type" "SOT-363H44"
			(at -2.3622 -10.1092 180)
			(unlocked yes)
			(layer "F.Fab")
			(hide yes)
			(effects
				(font
					(size 1.016 1.016)
					(thickness 0.1524)
				)
			)
		)
		(duplicate_pad_numbers_are_jumpers no)
		(fp_line
			(start 1.4478 1.7018)
			(end 1.4478 -1.7018)
			(stroke
				(width 0.1524)
				(type default)
			)
			(layer "F.SilkS")
		)
		(fp_line
			(start 1.4478 -1.7018)
			(end -1.4478 -1.7018)
			(stroke
				(width 0.1524)
				(type default)
			)
			(layer "F.SilkS")
		)
		(fp_line
			(start -1.27 1.524)
			(end -1.27 0.6604)
			(stroke
				(width 0.4826)
				(type default)
			)
			(layer "F.SilkS")
		)
		(fp_line
			(start -1.4478 1.7018)
			(end 1.4478 1.7018)
			(stroke
				(width 0.1524)
				(type default)
			)
			(layer "F.SilkS")
		)
		(fp_line
			(start -1.4478 -1.7018)
			(end -1.4478 1.7018)
			(stroke
				(width 0.1524)
				(type default)
			)
			(layer "F.SilkS")
		)
		(fp_poly
			(pts
				(xy -1.524 -1.778) (xy 1.524 -1.778) (xy 1.524 1.778) (xy -1.524 1.778)
			)
			(stroke
				(width 0)
				(type default)
			)
			(fill no)
			(layer "F.CrtYd")
		)
		(fp_poly
			(pts
				(xy -1.524 -1.778) (xy 1.524 -1.778) (xy 1.524 1.778) (xy -1.524 1.778)
			)
			(stroke
				(width 0)
				(type default)
			)
			(fill no)
			(layer "F.Fab")
		)
		(pad "1" smd rect
			(at -0.65024 0.9398 180)
			(size 0.4064 1.016)
			(layers "F.Cu" "F.Mask" "F.Paste")
			(net "GND")
		)
		(pad "2" smd rect
			(at 0 0.9398 180)
			(size 0.4064 1.016)
			(layers "F.Cu" "F.Mask" "F.Paste")
			(net "SW_PWR_R_HDD16")
		)
		(pad "3" smd rect
			(at 0.65024 0.9398 180)
			(size 0.4064 1.016)
			(layers "F.Cu" "F.Mask" "F.Paste")
			(net "SW_HDD_P16")
		)
		(pad "4" smd rect
			(at 0.65024 -0.9398 180)
			(size 0.4064 1.016)
			(layers "F.Cu" "F.Mask" "F.Paste")
			(net "GND")
		)
		(pad "5" smd rect
			(at 0 -0.9398 180)
			(size 0.4064 1.016)
			(layers "F.Cu" "F.Mask" "F.Paste")
			(net "SW_HDD_G16")
		)
		(pad "6" smd rect
			(at -0.65024 -0.9398 180)
			(size 0.4064 1.016)
			(layers "F.Cu" "F.Mask" "F.Paste")
			(net "SW_HDD_R16")
		)
	)
)
